(kicad_pcb
	(version 20260206)
	(generator "pcbnew")
	(generator_version "10.0")
	(general
		(thickness 1.6)
		(legacy_teardrops no)
	)
	(paper "A4")
	(title_block
		(title "Wiwynn_Tioga_Pass_MB.brd")
		(comment 1 "Tioga Pass / footprints 1627-1634 of 4770")
	)
	(layers
		(0 "F.Cu" signal "TOP")
		(4 "In1.Cu" signal "L2GND")
		(6 "In2.Cu" signal "L3")
		(8 "In3.Cu" signal "L4GND")
		(10 "In4.Cu" signal "L5")
		(12 "In5.Cu" signal "L6GND")
		(14 "In6.Cu" signal "L7VCC")
		(16 "In7.Cu" signal "L8VCC")
		(18 "In8.Cu" signal "L9GND")
		(20 "In9.Cu" signal "L10")
		(22 "In10.Cu" signal "L11GND")
		(24 "In11.Cu" signal "L12")
		(26 "In12.Cu" signal "L13GND")
		(2 "B.Cu" signal "BOTTOM")
		(9 "F.Adhes" user "F.Adhesive")
		(11 "B.Adhes" user "B.Adhesive")
		(13 "F.Paste" user "Package Geometry/Pastemask Top")
		(15 "B.Paste" user "Package Geometry/Pastemask Bottom")
		(5 "F.SilkS" user "Ref Des/Silkscreen Top")
		(7 "B.SilkS" user "Ref Des/Silkscreen Bottom")
		(1 "F.Mask" user "Board Geometry/Soldermask Top")
		(3 "B.Mask" user "Board Geometry/Soldermask Bottom")
		(17 "Dwgs.User" user "User.Drawings")
		(19 "Cmts.User" user "User.Comments")
		(21 "Eco1.User" user "User.Eco1")
		(23 "Eco2.User" user "User.Eco2")
		(25 "Edge.Cuts" user "Board Geometry/Outline")
		(27 "Margin" user)
		(31 "F.CrtYd" user "Package Geometry/Place Bound Top")
		(29 "B.CrtYd" user "Package Geometry/Place Bound Bottom")
		(35 "F.Fab" user "Ref Des/Assembly Top")
		(33 "B.Fab" user "Ref Des/Assembly Bottom")
	)
	(footprint ""
		(layer "F.Cu")
		(at 98.194368 -79.6036 180)
		(property "Reference" "C2D13"
			(at 0 0 180)
			(layer "F.SilkS")
			(hide yes)
			(effects
				(font
					(size 1.27 1.27)
				)
			)
		)
		(property "Value" ""
			(at 0 0 180)
			(layer "F.Fab")
			(effects
				(font
					(size 1.27 1.27)
				)
			)
		)
		(duplicate_pad_numbers_are_jumpers no)
		(fp_poly
			(pts
				(xy -0.4953 -0.2032) (xy 0.4953 -0.2032) (xy 0.4953 1.6002) (xy -0.4953 1.6002)
			)
			(stroke
				(width 0)
				(type default)
			)
			(fill no)
			(layer "F.CrtYd")
		)
		(fp_line
			(start 0.4953 1.6002)
			(end -0.4953 1.6002)
			(stroke
				(width 0.1)
				(type default)
			)
			(layer "F.Fab")
		)
		(fp_line
			(start 0.4953 -0.2032)
			(end 0.4953 1.6002)
			(stroke
				(width 0.1)
				(type default)
			)
			(layer "F.Fab")
		)
		(fp_line
			(start -0.4953 1.6002)
			(end -0.4953 -0.2032)
			(stroke
				(width 0.1)
				(type default)
			)
			(layer "F.Fab")
		)
		(fp_line
			(start -0.4953 -0.2032)
			(end 0.4953 -0.2032)
			(stroke
				(width 0.1)
				(type default)
			)
			(layer "F.Fab")
		)
		(pad "1" smd rect
			(at 0 0 180)
			(size 0.762 0.889)
			(layers "F.Cu" "F.Mask" "F.Paste")
			(net "PVCCIN_CPU1")
		)
		(pad "2" smd rect
			(at 0 1.397 180)
			(size 0.762 0.889)
			(layers "F.Cu" "F.Mask" "F.Paste")
			(net "GND")
		)
		(zone
			(layer "F.Cu")
			(hatch none 0.5)
			(connect_pads
				(clearance 0)
			)
			(min_thickness 0.25)
			(keepout
				(tracks not_allowed)
				(vias allowed)
				(pads allowed)
				(copperpour not_allowed)
				(footprints allowed)
			)
			(placement
				(enabled no)
				(sheetname "")
			)
			(fill
				(thermal_gap 0.5)
				(thermal_bridge_width 0.5)
				(island_removal_mode 0)
			)
			(polygon
				(pts
					(xy 98.575368 -80.0481) (xy 97.813368 -80.0481) (xy 97.813368 -80.5561) (xy 98.575368 -80.5561)
				)
			)
		)
	)
	(footprint ""
		(layer "F.Cu")
		(at 153.543 -12.954 -90)
		(property "Reference" "C3G3"
			(at 0 0 270)
			(layer "F.SilkS")
			(hide yes)
			(effects
				(font
					(size 1.27 1.27)
				)
			)
		)
		(property "Value" ""
			(at 0 0 270)
			(layer "F.Fab")
			(effects
				(font
					(size 1.27 1.27)
				)
			)
		)
		(duplicate_pad_numbers_are_jumpers no)
		(fp_poly
			(pts
				(xy -0.4953 -0.2032) (xy 0.4953 -0.2032) (xy 0.4953 1.6002) (xy -0.4953 1.6002)
			)
			(stroke
				(width 0)
				(type default)
			)
			(fill no)
			(layer "F.CrtYd")
		)
		(fp_line
			(start -0.4953 1.6002)
			(end -0.4953 -0.2032)
			(stroke
				(width 0.1)
				(type default)
			)
			(layer "F.Fab")
		)
		(fp_line
			(start 0.4953 1.6002)
			(end -0.4953 1.6002)
			(stroke
				(width 0.1)
				(type default)
			)
			(layer "F.Fab")
		)
		(fp_line
			(start -0.4953 -0.2032)
			(end 0.4953 -0.2032)
			(stroke
				(width 0.1)
				(type default)
			)
			(layer "F.Fab")
		)
		(fp_line
			(start 0.4953 -0.2032)
			(end 0.4953 1.6002)
			(stroke
				(width 0.1)
				(type default)
			)
			(layer "F.Fab")
		)
		(pad "1" smd rect
			(at 0 0 270)
			(size 0.762 0.889)
			(layers "F.Cu" "F.Mask" "F.Paste")
			(net "PVPP_GHJ")
		)
		(pad "2" smd rect
			(at 0 1.397 270)
			(size 0.762 0.889)
			(layers "F.Cu" "F.Mask" "F.Paste")
			(net "GND")
		)
		(zone
			(layer "F.Cu")
			(hatch none 0.5)
			(connect_pads
				(clearance 0)
			)
			(min_thickness 0.25)
			(keepout
				(tracks not_allowed)
				(vias allowed)
				(pads allowed)
				(copperpour not_allowed)
				(footprints allowed)
			)
			(placement
				(enabled no)
				(sheetname "")
			)
			(fill
				(thermal_gap 0.5)
				(thermal_bridge_width 0.5)
				(island_removal_mode 0)
			)
			(polygon
				(pts
					(xy 153.0985 -13.335) (xy 153.0985 -12.573) (xy 152.5905 -12.573) (xy 152.5905 -13.335)
				)
			)
		)
	)
	(footprint ""
		(layer "F.Cu")
		(at 452.312024 -146.55546)
		(property "Reference" "R25W185"
			(at -0.8382 -0.67818 0)
			(unlocked yes)
			(layer "F.SilkS")
			(effects
				(font
					(size 0.4064 0.254)
					(thickness 0.1524)
				)
				(justify left)
			)
		)
		(property "Value" ""
			(at 0 0 0)
			(layer "F.Fab")
			(effects
				(font
					(size 1.27 1.27)
				)
			)
		)
		(duplicate_pad_numbers_are_jumpers no)
		(fp_poly
			(pts
				(xy -0.2794 -0.1016) (xy 0.2794 -0.1016) (xy 0.2794 0.9906) (xy -0.2794 0.9906)
			)
			(stroke
				(width 0)
				(type default)
			)
			(fill no)
			(layer "F.CrtYd")
		)
		(fp_line
			(start -0.2794 -0.1016)
			(end -0.2794 0.9906)
			(stroke
				(width 0.1)
				(type default)
			)
			(layer "F.Fab")
		)
		(fp_line
			(start -0.2794 0.9906)
			(end 0.2794 0.9906)
			(stroke
				(width 0.1)
				(type default)
			)
			(layer "F.Fab")
		)
		(fp_line
			(start 0.2794 -0.1016)
			(end -0.2794 -0.1016)
			(stroke
				(width 0.1)
				(type default)
			)
			(layer "F.Fab")
		)
		(fp_line
			(start 0.2794 0.9906)
			(end 0.2794 -0.1016)
			(stroke
				(width 0.1)
				(type default)
			)
			(layer "F.Fab")
		)
		(pad "1" smd rect
			(at 0 0)
			(size 0.508 0.508)
			(layers "F.Cu" "F.Mask" "F.Paste")
			(net "P3V3_STBY")
		)
		(pad "2" smd rect
			(at 0 0.889)
			(size 0.508 0.508)
			(layers "F.Cu" "F.Mask" "F.Paste")
			(net "BMC_JTAG_SEL")
		)
		(zone
			(layer "F.Cu")
			(hatch none 0.5)
			(connect_pads
				(clearance 0)
			)
			(min_thickness 0.25)
			(keepout
				(tracks allowed)
				(vias not_allowed)
				(pads allowed)
				(copperpour not_allowed)
				(footprints allowed)
			)
			(placement
				(enabled no)
				(sheetname "")
			)
			(fill
				(thermal_gap 0.5)
				(thermal_bridge_width 0.5)
				(island_removal_mode 0)
			)
			(polygon
				(pts
					(xy 452.058024 -146.30146) (xy 452.566024 -146.30146) (xy 452.566024 -145.92046) (xy 452.058024 -145.92046)
				)
			)
		)
		(zone
			(layer "F.Cu")
			(hatch none 0.5)
			(connect_pads
				(clearance 0)
			)
			(min_thickness 0.25)
			(keepout
				(tracks not_allowed)
				(vias allowed)
				(pads allowed)
				(copperpour not_allowed)
				(footprints allowed)
			)
			(placement
				(enabled no)
				(sheetname "")
			)
			(fill
				(thermal_gap 0.5)
				(thermal_bridge_width 0.5)
				(island_removal_mode 0)
			)
			(polygon
				(pts
					(xy 452.058024 -145.92046) (xy 452.566024 -145.92046) (xy 452.566024 -146.30146) (xy 452.058024 -146.30146)
				)
			)
		)
	)
	(footprint ""
		(layer "F.Cu")
		(at 111.000032 -140.208 90)
		(property "Reference" "C3A6"
			(at 1.848866 0.752348 90)
			(unlocked yes)
			(layer "F.SilkS")
			(effects
				(font
					(size 1.27 0.9652)
					(thickness 0.1524)
				)
			)
		)
		(property "Value" ""
			(at 0 0 90)
			(layer "F.Fab")
			(effects
				(font
					(size 1.27 1.27)
				)
			)
		)
		(duplicate_pad_numbers_are_jumpers no)
		(fp_rect
			(start -0.500126 1.598422)
			(end 0.500126 -0.201422)
			(stroke
				(width 0)
				(type default)
			)
			(fill no)
			(layer "F.CrtYd")
		)
		(fp_line
			(start 0.500126 -0.201422)
			(end 0.500126 1.598422)
			(stroke
				(width 0.1)
				(type default)
			)
			(layer "F.Fab")
		)
		(fp_line
			(start -0.500126 -0.201422)
			(end 0.500126 -0.201422)
			(stroke
				(width 0.1)
				(type default)
			)
			(layer "F.Fab")
		)
		(fp_line
			(start 0.500126 1.598422)
			(end -0.500126 1.598422)
			(stroke
				(width 0.1)
				(type default)
			)
			(layer "F.Fab")
		)
		(fp_line
			(start -0.500126 1.598422)
			(end -0.500126 -0.201422)
			(stroke
				(width 0.1)
				(type default)
			)
			(layer "F.Fab")
		)
		(pad "1" smd rect
			(at 0 0)
			(size 0.889 0.9906)
			(layers "F.Cu" "F.Mask" "F.Paste")
			(net "PVDDQ_KLM")
		)
		(pad "2" smd rect
			(at 0 1.397)
			(size 0.889 0.9906)
			(layers "F.Cu" "F.Mask" "F.Paste")
			(net "GND")
		)
		(zone
			(layer "F.Cu")
			(hatch none 0.5)
			(connect_pads
				(clearance 0)
			)
			(min_thickness 0.25)
			(keepout
				(tracks allowed)
				(vias not_allowed)
				(pads allowed)
				(copperpour not_allowed)
				(footprints allowed)
			)
			(placement
				(enabled no)
				(sheetname "")
			)
			(fill
				(thermal_gap 0.5)
				(thermal_bridge_width 0.5)
				(island_removal_mode 0)
			)
			(polygon
				(pts
					(xy 111.952532 -139.7127) (xy 111.952532 -140.7033) (xy 111.444532 -140.7033) (xy 111.444532 -139.7127)
				)
			)
		)
		(zone
			(layer "F.Cu")
			(hatch none 0.5)
			(connect_pads
				(clearance 0)
			)
			(min_thickness 0.25)
			(keepout
				(tracks not_allowed)
				(vias allowed)
				(pads allowed)
				(copperpour not_allowed)
				(footprints allowed)
			)
			(placement
				(enabled no)
				(sheetname "")
			)
			(fill
				(thermal_gap 0.5)
				(thermal_bridge_width 0.5)
				(island_removal_mode 0)
			)
			(polygon
				(pts
					(xy 111.952532 -139.7127) (xy 111.952532 -140.7033) (xy 111.444532 -140.7033) (xy 111.444532 -139.7127)
				)
			)
		)
	)
	(footprint ""
		(layer "F.Cu")
		(at 202.273154 -61.205364 -90)
		(property "Reference" "RT4"
			(at 0 0 270)
			(layer "F.SilkS")
			(hide yes)
			(effects
				(font
					(size 1.27 1.27)
				)
			)
		)
		(property "Value" "*"
			(at -0.0254 -2.6289 270)
			(unlocked yes)
			(layer "F.Fab")
			(hide yes)
			(effects
				(font
					(size 1.27 1.016)
					(thickness 0.1524)
				)
			)
		)
		(property "Device Type" "1R3F-GP_RCL_GP-1R3F-GP,64.1R00A"
			(at -0.0254 -4.1529 270)
			(unlocked yes)
			(layer "F.Fab")
			(hide yes)
			(effects
				(font
					(size 1.27 1.016)
					(thickness 0.1524)
				)
			)
		)
		(duplicate_pad_numbers_are_jumpers no)
		(fp_line
			(start -0.4826 0)
			(end -0.2032 0)
			(stroke
				(width 0.2032)
				(type default)
			)
			(layer "F.SilkS")
		)
		(fp_line
			(start 0.2032 0)
			(end 0.4826 0)
			(stroke
				(width 0.2032)
				(type default)
			)
			(layer "F.SilkS")
		)
		(fp_rect
			(start -0.5842 1.3335)
			(end 0.5842 -1.3335)
			(stroke
				(width 0)
				(type default)
			)
			(fill no)
			(layer "F.CrtYd")
		)
		(fp_rect
			(start -0.5842 1.3335)
			(end 0.5842 -1.3335)
			(stroke
				(width 0)
				(type default)
			)
			(fill no)
			(layer "F.Fab")
		)
		(pad "1" smd custom
			(at 0 -0.762 270)
			(size 0.2159 0.2159)
			(layers "F.Cu" "F.Mask" "F.Paste")
			(net "VR_PVCCIN_CPU0_PHASE2_RC")
			(options
				(clearance outline)
				(anchor circle)
			)
			(primitives
				(gr_poly
					(pts
						(arc
							(start -0.3302 -0.4318)
							(mid -0.402042 -0.402042)
							(end -0.4318 -0.3302)
						)
						(arc
							(start -0.4318 0.3302)
							(mid -0.402042 0.402042)
							(end -0.3302 0.4318)
						)
						(arc
							(start 0.3302 0.4318)
							(mid 0.402042 0.402042)
							(end 0.4318 0.3302)
						)
						(arc
							(start 0.4318 -0.3302)
							(mid 0.402042 -0.402042)
							(end 0.3302 -0.4318)
						)
					)
					(width 0)
					(fill yes)
				)
			)
		)
		(pad "2" smd custom
			(at 0 0.762 270)
			(size 0.2159 0.2159)
			(layers "F.Cu" "F.Mask" "F.Paste")
			(net "GND")
			(options
				(clearance outline)
				(anchor circle)
			)
			(primitives
				(gr_poly
					(pts
						(arc
							(start -0.3302 -0.4318)
							(mid -0.402042 -0.402042)
							(end -0.4318 -0.3302)
						)
						(arc
							(start -0.4318 0.3302)
							(mid -0.402042 0.402042)
							(end -0.3302 0.4318)
						)
						(arc
							(start 0.3302 0.4318)
							(mid 0.402042 0.402042)
							(end 0.4318 0.3302)
						)
						(arc
							(start 0.4318 -0.3302)
							(mid 0.402042 -0.402042)
							(end 0.3302 -0.4318)
						)
					)
					(width 0)
					(fill yes)
				)
			)
		)
	)
	(footprint ""
		(layer "F.Cu")
		(at 23.0505 -67.848988 90)
		(property "Reference" "R1W21"
			(at -0.8382 -0.67818 90)
			(unlocked yes)
			(layer "F.SilkS")
			(effects
				(font
					(size 0.4064 0.254)
					(thickness 0.1524)
				)
				(justify left)
			)
		)
		(property "Value" ""
			(at 0 0 90)
			(layer "F.Fab")
			(effects
				(font
					(size 1.27 1.27)
				)
			)
		)
		(duplicate_pad_numbers_are_jumpers no)
		(fp_poly
			(pts
				(xy -0.2794 -0.1016) (xy 0.2794 -0.1016) (xy 0.2794 0.9906) (xy -0.2794 0.9906)
			)
			(stroke
				(width 0)
				(type default)
			)
			(fill no)
			(layer "F.CrtYd")
		)
		(fp_line
			(start 0.2794 -0.1016)
			(end -0.2794 -0.1016)
			(stroke
				(width 0.1)
				(type default)
			)
			(layer "F.Fab")
		)
		(fp_line
			(start -0.2794 -0.1016)
			(end -0.2794 0.9906)
			(stroke
				(width 0.1)
				(type default)
			)
			(layer "F.Fab")
		)
		(fp_line
			(start 0.2794 0.9906)
			(end 0.2794 -0.1016)
			(stroke
				(width 0.1)
				(type default)
			)
			(layer "F.Fab")
		)
		(fp_line
			(start -0.2794 0.9906)
			(end 0.2794 0.9906)
			(stroke
				(width 0.1)
				(type default)
			)
			(layer "F.Fab")
		)
		(pad "1" smd rect
			(at 0 0 90)
			(size 0.508 0.508)
			(layers "F.Cu" "F.Mask" "F.Paste")
			(net "GND")
		)
		(pad "2" smd rect
			(at 0 0.889 90)
			(size 0.508 0.508)
			(layers "F.Cu" "F.Mask" "F.Paste")
			(net "TEMP_SENSOR_E")
		)
		(zone
			(layer "F.Cu")
			(hatch none 0.5)
			(connect_pads
				(clearance 0)
			)
			(min_thickness 0.25)
			(keepout
				(tracks allowed)
				(vias not_allowed)
				(pads allowed)
				(copperpour not_allowed)
				(footprints allowed)
			)
			(placement
				(enabled no)
				(sheetname "")
			)
			(fill
				(thermal_gap 0.5)
				(thermal_bridge_width 0.5)
				(island_removal_mode 0)
			)
			(polygon
				(pts
					(xy 23.3045 -67.594988) (xy 23.3045 -68.102988) (xy 23.6855 -68.102988) (xy 23.6855 -67.594988)
				)
			)
		)
		(zone
			(layer "F.Cu")
			(hatch none 0.5)
			(connect_pads
				(clearance 0)
			)
			(min_thickness 0.25)
			(keepout
				(tracks not_allowed)
				(vias allowed)
				(pads allowed)
				(copperpour not_allowed)
				(footprints allowed)
			)
			(placement
				(enabled no)
				(sheetname "")
			)
			(fill
				(thermal_gap 0.5)
				(thermal_bridge_width 0.5)
				(island_removal_mode 0)
			)
			(polygon
				(pts
					(xy 23.6855 -67.594988) (xy 23.6855 -68.102988) (xy 23.3045 -68.102988) (xy 23.3045 -67.594988)
				)
			)
		)
	)
	(footprint ""
		(layer "F.Cu")
		(at 474.98 -35.7505 180)
		(property "Reference" "R2T46"
			(at 0 0 180)
			(layer "F.SilkS")
			(hide yes)
			(effects
				(font
					(size 1.27 1.27)
				)
			)
		)
		(property "Value" ""
			(at 0 0 180)
			(layer "F.Fab")
			(effects
				(font
					(size 1.27 1.27)
				)
			)
		)
		(duplicate_pad_numbers_are_jumpers no)
		(fp_poly
			(pts
				(xy -0.2794 -0.1016) (xy 0.2794 -0.1016) (xy 0.2794 0.9906) (xy -0.2794 0.9906)
			)
			(stroke
				(width 0)
				(type default)
			)
			(fill no)
			(layer "F.CrtYd")
		)
		(fp_line
			(start 0.2794 0.9906)
			(end 0.2794 -0.1016)
			(stroke
				(width 0.1)
				(type default)
			)
			(layer "F.Fab")
		)
		(fp_line
			(start 0.2794 -0.1016)
			(end -0.2794 -0.1016)
			(stroke
				(width 0.1)
				(type default)
			)
			(layer "F.Fab")
		)
		(fp_line
			(start -0.2794 0.9906)
			(end 0.2794 0.9906)
			(stroke
				(width 0.1)
				(type default)
			)
			(layer "F.Fab")
		)
		(fp_line
			(start -0.2794 -0.1016)
			(end -0.2794 0.9906)
			(stroke
				(width 0.1)
				(type default)
			)
			(layer "F.Fab")
		)
		(pad "1" smd rect
			(at 0 0 180)
			(size 0.508 0.508)
			(layers "F.Cu" "F.Mask" "F.Paste")
			(net "CLK_50M_CKMNG_BMC_1_R")
		)
		(pad "2" smd rect
			(at 0 0.889 180)
			(size 0.508 0.508)
			(layers "F.Cu" "F.Mask" "F.Paste")
			(net "CLK_50M_CKMNG_BMC_1")
		)
		(zone
			(layer "F.Cu")
			(hatch none 0.5)
			(connect_pads
				(clearance 0)
			)
			(min_thickness 0.25)
			(keepout
				(tracks not_allowed)
				(vias allowed)
				(pads allowed)
				(copperpour not_allowed)
				(footprints allowed)
			)
			(placement
				(enabled no)
				(sheetname "")
			)
			(fill
				(thermal_gap 0.5)
				(thermal_bridge_width 0.5)
				(island_removal_mode 0)
			)
			(polygon
				(pts
					(xy 475.234 -36.3855) (xy 474.726 -36.3855) (xy 474.726 -36.0045) (xy 475.234 -36.0045)
				)
			)
		)
		(zone
			(layer "F.Cu")
			(hatch none 0.5)
			(connect_pads
				(clearance 0)
			)
			(min_thickness 0.25)
			(keepout
				(tracks allowed)
				(vias not_allowed)
				(pads allowed)
				(copperpour not_allowed)
				(footprints allowed)
			)
			(placement
				(enabled no)
				(sheetname "")
			)
			(fill
				(thermal_gap 0.5)
				(thermal_bridge_width 0.5)
				(island_removal_mode 0)
			)
			(polygon
				(pts
					(xy 475.234 -36.0045) (xy 474.726 -36.0045) (xy 474.726 -36.3855) (xy 475.234 -36.3855)
				)
			)
		)
	)
	(footprint ""
		(layer "F.Cu")
		(at 205.036928 -65.159382)
		(property "Reference" "L4D3"
			(at 3.378708 -4.251706 0)
			(unlocked yes)
			(layer "F.SilkS")
			(effects
				(font
					(size 0.4064 0.254)
					(thickness 0.1524)
				)
			)
		)
		(property "Value" ""
			(at 0 0 0)
			(layer "F.Fab")
			(effects
				(font
					(size 1.27 1.27)
				)
			)
		)
		(duplicate_pad_numbers_are_jumpers no)
		(fp_line
			(start -1.1303 -3.199892)
			(end 8.3693 -3.199892)
			(stroke
				(width 0.1524)
				(type default)
			)
			(layer "F.SilkS")
		)
		(fp_line
			(start -1.1303 -1.6637)
			(end -1.1303 -3.199892)
			(stroke
				(width 0.1524)
				(type default)
			)
			(layer "F.SilkS")
		)
		(fp_line
			(start -1.1303 3.199892)
			(end -1.1303 1.6637)
			(stroke
				(width 0.1524)
				(type default)
			)
			(layer "F.SilkS")
		)
		(fp_line
			(start 8.3693 -3.199892)
			(end 8.3693 -1.6637)
			(stroke
				(width 0.1524)
				(type default)
			)
			(layer "F.SilkS")
		)
		(fp_line
			(start 8.3693 1.6637)
			(end 8.3693 3.199892)
			(stroke
				(width 0.1524)
				(type default)
			)
			(layer "F.SilkS")
		)
		(fp_line
			(start 8.3693 3.199892)
			(end -1.1303 3.199892)
			(stroke
				(width 0.1524)
				(type default)
			)
			(layer "F.SilkS")
		)
		(fp_rect
			(start -1.1303 3.199892)
			(end 8.3693 -3.199892)
			(stroke
				(width 0)
				(type default)
			)
			(fill no)
			(layer "F.CrtYd")
		)
		(fp_line
			(start -1.1303 -3.199892)
			(end 8.3693 -3.199892)
			(stroke
				(width 0.1)
				(type default)
			)
			(layer "F.Fab")
		)
		(fp_line
			(start -1.1303 3.199892)
			(end -1.1303 -3.199892)
			(stroke
				(width 0.1)
				(type default)
			)
			(layer "F.Fab")
		)
		(fp_line
			(start 8.3693 -3.199892)
			(end 8.3693 3.199892)
			(stroke
				(width 0.1)
				(type default)
			)
			(layer "F.Fab")
		)
		(fp_line
			(start 8.3693 3.199892)
			(end -1.1303 3.199892)
			(stroke
				(width 0.1)
				(type default)
			)
			(layer "F.Fab")
		)
		(pad "1" smd rect
			(at 0 0)
			(size 3.683 2.667)
			(layers "F.Cu" "F.Mask" "F.Paste")
			(net "VR_PVCCIN_CPU0_PHASE2")
		)
		(pad "2" smd rect
			(at 7.239 0)
			(size 3.683 2.667)
			(layers "F.Cu" "F.Mask" "F.Paste")
			(net "PVCCIN_CPU0")
		)
	)
)
